# S9S_MB_2U (Grand Teton) — schematic netlist excerpt (pin names and nets, part order shuffled) for the footprints in the layout excerpt that follows; sources: Cadence DE-HDL packaged netlist, KiCad conversion of 03242023_DA0F0TMBIJ0_F0T_Motherboard_J_brd_V01_OCP.brd

R3004  Q_RES  2.2K 5% EMPTY  pkg 0402LF  page 241 : A = SMB_2_BMC_GPU_SDA ; B = P3V3_AUX
C441  Q_CAP  22UF 4V 20% X6S  pkg C0402  page 77 : A = PVCCFA_EHV_FIVRA_CPU1 ; B = GND

(kicad_pcb
	(version 20260206)
	(generator "pcbnew")
	(generator_version "10.0")
	(general
		(thickness 1.6)
		(legacy_teardrops no)
	)
	(paper "A4")
	(title_block
		(title "03242023_DA0F0TMBIJ0_F0T_Motherboard_J_brd_V01_OCP.brd")
		(comment 1 "Grand Teton / footprints 3896-3897 of 6105")
	)
	(layers
		(0 "F.Cu" signal "TOP")
		(4 "In1.Cu" signal "GND")
		(6 "In2.Cu" signal "IN1")
		(8 "In3.Cu" signal "GND1")
		(10 "In4.Cu" signal "IN2")
		(12 "In5.Cu" signal "GND2")
		(14 "In6.Cu" signal "IN3")
		(16 "In7.Cu" signal "GND3")
		(18 "In8.Cu" signal "VCC")
		(20 "In9.Cu" signal "VCC1")
		(22 "In10.Cu" signal "GND4")
		(24 "In11.Cu" signal "IN4")
		(26 "In12.Cu" signal "GND5")
		(28 "In13.Cu" signal "IN5")
		(30 "In14.Cu" signal "GND6")
		(32 "In15.Cu" signal "IN6")
		(34 "In16.Cu" signal "GND7")
		(2 "B.Cu" signal "BOTTOM")
		(9 "F.Adhes" user "F.Adhesive")
		(11 "B.Adhes" user "B.Adhesive")
		(13 "F.Paste" user "Package Geometry/Pastemask Top")
		(15 "B.Paste" user "Package Geometry/Pastemask Bottom")
		(5 "F.SilkS" user "Ref Des/Silkscreen Top")
		(7 "B.SilkS" user "Ref Des/Silkscreen Bottom")
		(1 "F.Mask" user "Board Geometry/Soldermask Top")
		(3 "B.Mask" user "Board Geometry/Soldermask Bottom")
		(17 "Dwgs.User" user "User.Drawings")
		(19 "Cmts.User" user "User.Comments")
		(21 "Eco1.User" user "User.Eco1")
		(23 "Eco2.User" user "User.Eco2")
		(25 "Edge.Cuts" user "Board Geometry/Outline")
		(27 "Margin" user)
		(31 "F.CrtYd" user "Package Geometry/Place Bound Top")
		(29 "B.CrtYd" user "Package Geometry/Place Bound Bottom")
		(35 "F.Fab" user "Ref Des/Assembly Top")
		(33 "B.Fab" user "Ref Des/Assembly Bottom")
	)
	(footprint ""
		(layer "F.Cu")
		(at 117.526816 -260.36524 -90)
		(property "Reference" "C441"
			(at 0 0 270)
			(layer "F.SilkS")
			(hide yes)
			(effects
				(font
					(size 1.27 1.27)
				)
			)
		)
		(property "Value" ""
			(at 0 0 270)
			(layer "F.Fab")
			(effects
				(font
					(size 1.27 1.27)
				)
			)
		)
		(duplicate_pad_numbers_are_jumpers no)
		(fp_line
			(start -0.7874 0.4064)
			(end -0.7874 -0.4064)
			(stroke
				(width 0.1524)
				(type default)
			)
			(layer "F.SilkS")
		)
		(fp_line
			(start 0.7874 0.4064)
			(end -0.7874 0.4064)
			(stroke
				(width 0.1524)
				(type default)
			)
			(layer "F.SilkS")
		)
		(fp_line
			(start -0.7874 -0.4064)
			(end 0.7874 -0.4064)
			(stroke
				(width 0.1524)
				(type default)
			)
			(layer "F.SilkS")
		)
		(fp_line
			(start 0.7874 -0.4064)
			(end 0.7874 0.4064)
			(stroke
				(width 0.1524)
				(type default)
			)
			(layer "F.SilkS")
		)
		(fp_line
			(start -0.67945 0.3048)
			(end -0.67945 -0.305054)
			(stroke
				(width 0.1)
				(type default)
			)
			(layer "F.Fab")
		)
		(fp_line
			(start -0.12065 0.3048)
			(end -0.67945 0.3048)
			(stroke
				(width 0.1)
				(type default)
			)
			(layer "F.Fab")
		)
		(fp_line
			(start 0.120396 0.3048)
			(end 0.120396 0.2794)
			(stroke
				(width 0.1)
				(type default)
			)
			(layer "F.Fab")
		)
		(fp_line
			(start 0.67945 0.3048)
			(end 0.120396 0.3048)
			(stroke
				(width 0.1)
				(type default)
			)
			(layer "F.Fab")
		)
		(fp_line
			(start -0.12065 0.2794)
			(end -0.12065 0.3048)
			(stroke
				(width 0.1)
				(type default)
			)
			(layer "F.Fab")
		)
		(fp_line
			(start 0.120396 0.2794)
			(end -0.12065 0.2794)
			(stroke
				(width 0.1)
				(type default)
			)
			(layer "F.Fab")
		)
		(fp_line
			(start -0.12065 -0.2794)
			(end 0.12065 -0.2794)
			(stroke
				(width 0.1)
				(type default)
			)
			(layer "F.Fab")
		)
		(fp_line
			(start 0.12065 -0.2794)
			(end 0.12065 -0.3048)
			(stroke
				(width 0.1)
				(type default)
			)
			(layer "F.Fab")
		)
		(fp_line
			(start 0.12065 -0.3048)
			(end 0.67945 -0.3048)
			(stroke
				(width 0.1)
				(type default)
			)
			(layer "F.Fab")
		)
		(fp_line
			(start 0.67945 -0.3048)
			(end 0.67945 0.3048)
			(stroke
				(width 0.1)
				(type default)
			)
			(layer "F.Fab")
		)
		(fp_line
			(start -0.67945 -0.305054)
			(end -0.12065 -0.305054)
			(stroke
				(width 0.1)
				(type default)
			)
			(layer "F.Fab")
		)
		(fp_line
			(start -0.12065 -0.305054)
			(end -0.12065 -0.2794)
			(stroke
				(width 0.1)
				(type default)
			)
			(layer "F.Fab")
		)
		(pad "1" smd circle
			(at -0.40005 0 270)
			(size 0 0)
			(layers "F.Cu" "F.Mask" "F.Paste")
			(net "PVCCFA_EHV_FIVRA_CPU1")
		)
		(pad "2" smd circle
			(at 0.40005 0 270)
			(size 0 0)
			(layers "F.Cu" "F.Mask" "F.Paste")
			(net "GND")
		)
	)
	(footprint ""
		(layer "F.Cu")
		(at 30.71114 -438.161938 -90)
		(property "Reference" "R3004"
			(at 0 0 270)
			(layer "F.SilkS")
			(hide yes)
			(effects
				(font
					(size 1.27 1.27)
				)
			)
		)
		(property "Value" ""
			(at 0 0 270)
			(layer "F.Fab")
			(effects
				(font
					(size 1.27 1.27)
				)
			)
		)
		(duplicate_pad_numbers_are_jumpers no)
		(fp_line
			(start -0.7874 0.4064)
			(end -0.7874 -0.4064)
			(stroke
				(width 0.1524)
				(type default)
			)
			(layer "F.SilkS")
		)
		(fp_line
			(start 0.7874 0.4064)
			(end -0.7874 0.4064)
			(stroke
				(width 0.1524)
				(type default)
			)
			(layer "F.SilkS")
		)
		(fp_line
			(start -0.7874 -0.4064)
			(end 0.7874 -0.4064)
			(stroke
				(width 0.1524)
				(type default)
			)
			(layer "F.SilkS")
		)
		(fp_line
			(start 0.7874 -0.4064)
			(end 0.7874 0.4064)
			(stroke
				(width 0.1524)
				(type default)
			)
			(layer "F.SilkS")
		)
		(fp_line
			(start -0.67945 0.3048)
			(end -0.67945 -0.305054)
			(stroke
				(width 0.1)
				(type default)
			)
			(layer "F.Fab")
		)
		(fp_line
			(start -0.12065 0.3048)
			(end -0.67945 0.3048)
			(stroke
				(width 0.1)
				(type default)
			)
			(layer "F.Fab")
		)
		(fp_line
			(start 0.120396 0.3048)
			(end 0.120396 0.2794)
			(stroke
				(width 0.1)
				(type default)
			)
			(layer "F.Fab")
		)
		(fp_line
			(start 0.67945 0.3048)
			(end 0.120396 0.3048)
			(stroke
				(width 0.1)
				(type default)
			)
			(layer "F.Fab")
		)
		(fp_line
			(start -0.12065 0.2794)
			(end -0.12065 0.3048)
			(stroke
				(width 0.1)
				(type default)
			)
			(layer "F.Fab")
		)
		(fp_line
			(start 0.120396 0.2794)
			(end -0.12065 0.2794)
			(stroke
				(width 0.1)
				(type default)
			)
			(layer "F.Fab")
		)
		(fp_line
			(start -0.12065 -0.2794)
			(end 0.12065 -0.2794)
			(stroke
				(width 0.1)
				(type default)
			)
			(layer "F.Fab")
		)
		(fp_line
			(start 0.12065 -0.2794)
			(end 0.12065 -0.3048)
			(stroke
				(width 0.1)
				(type default)
			)
			(layer "F.Fab")
		)
		(fp_line
			(start 0.12065 -0.3048)
			(end 0.67945 -0.3048)
			(stroke
				(width 0.1)
				(type default)
			)
			(layer "F.Fab")
		)
		(fp_line
			(start 0.67945 -0.3048)
			(end 0.67945 0.3048)
			(stroke
				(width 0.1)
				(type default)
			)
			(layer "F.Fab")
		)
		(fp_line
			(start -0.67945 -0.305054)
			(end -0.12065 -0.305054)
			(stroke
				(width 0.1)
				(type default)
			)
			(layer "F.Fab")
		)
		(fp_line
			(start -0.12065 -0.305054)
			(end -0.12065 -0.2794)
			(stroke
				(width 0.1)
				(type default)
			)
			(layer "F.Fab")
		)
		(pad "1" smd circle
			(at -0.40005 0 270)
			(size 0 0)
			(layers "F.Cu" "F.Mask" "F.Paste")
			(net "SMB_2_BMC_GPU_SDA")
		)
		(pad "2" smd circle
			(at 0.40005 0 270)
			(size 0 0)
			(layers "F.Cu" "F.Mask" "F.Paste")
			(net "P3V3_AUX")
		)
	)
)
